(kicad_pcb
	(version 20260206)
	(generator "pcbnew")
	(generator_version "10.0")
	(general
		(thickness 1.6)
		(legacy_teardrops no)
	)
	(paper "A4")
	(title_block
		(title "12092022_DA0F0TMDCD0_F0T_Management_Board_D_brd_V3_OCP.brd")
		(comment 1 "Grand Teton / footprints 243-249 of 1440")
	)
	(layers
		(0 "F.Cu" signal "TOP")
		(4 "In1.Cu" signal "GND")
		(6 "In2.Cu" signal "IN1")
		(8 "In3.Cu" signal "GND1")
		(10 "In4.Cu" signal "IN2")
		(12 "In5.Cu" signal "VCC")
		(14 "In6.Cu" signal "VCC1")
		(16 "In7.Cu" signal "IN3")
		(18 "In8.Cu" signal "GND2")
		(20 "In9.Cu" signal "IN4")
		(22 "In10.Cu" signal "GND3")
		(2 "B.Cu" signal "BOTTOM")
		(9 "F.Adhes" user "F.Adhesive")
		(11 "B.Adhes" user "B.Adhesive")
		(13 "F.Paste" user "Package Geometry/Pastemask Top")
		(15 "B.Paste" user "Package Geometry/Pastemask Bottom")
		(5 "F.SilkS" user "Ref Des/Silkscreen Top")
		(7 "B.SilkS" user "Ref Des/Silkscreen Bottom")
		(1 "F.Mask" user "Board Geometry/Soldermask Top")
		(3 "B.Mask" user "Board Geometry/Soldermask Bottom")
		(17 "Dwgs.User" user "User.Drawings")
		(19 "Cmts.User" user "User.Comments")
		(21 "Eco1.User" user "User.Eco1")
		(23 "Eco2.User" user "User.Eco2")
		(25 "Edge.Cuts" user "Board Geometry/Outline")
		(27 "Margin" user)
		(31 "F.CrtYd" user "Package Geometry/Place Bound Top")
		(29 "B.CrtYd" user "Package Geometry/Place Bound Bottom")
		(35 "F.Fab" user "Ref Des/Assembly Top")
		(33 "B.Fab" user "Ref Des/Assembly Bottom")
	)
	(footprint ""
		(layer "F.Cu")
		(at 45.256196 -65.918334 90)
		(property "Reference" "R21"
			(at 0 0 90)
			(layer "F.SilkS")
			(hide yes)
			(effects
				(font
					(size 1.27 1.27)
				)
			)
		)
		(property "Value" ""
			(at 0 0 90)
			(layer "F.Fab")
			(effects
				(font
					(size 1.27 1.27)
				)
			)
		)
		(duplicate_pad_numbers_are_jumpers no)
		(fp_line
			(start 0.7874 -0.4064)
			(end 0.7874 0.4064)
			(stroke
				(width 0.1524)
				(type default)
			)
			(layer "F.SilkS")
		)
		(fp_line
			(start -0.7874 -0.4064)
			(end 0.7874 -0.4064)
			(stroke
				(width 0.1524)
				(type default)
			)
			(layer "F.SilkS")
		)
		(fp_line
			(start 0.7874 0.4064)
			(end -0.7874 0.4064)
			(stroke
				(width 0.1524)
				(type default)
			)
			(layer "F.SilkS")
		)
		(fp_line
			(start -0.7874 0.4064)
			(end -0.7874 -0.4064)
			(stroke
				(width 0.1524)
				(type default)
			)
			(layer "F.SilkS")
		)
		(fp_line
			(start -0.12065 -0.305054)
			(end -0.12065 -0.2794)
			(stroke
				(width 0.1)
				(type default)
			)
			(layer "F.Fab")
		)
		(fp_line
			(start -0.67945 -0.305054)
			(end -0.12065 -0.305054)
			(stroke
				(width 0.1)
				(type default)
			)
			(layer "F.Fab")
		)
		(fp_line
			(start 0.67945 -0.3048)
			(end 0.67945 0.3048)
			(stroke
				(width 0.1)
				(type default)
			)
			(layer "F.Fab")
		)
		(fp_line
			(start 0.12065 -0.3048)
			(end 0.67945 -0.3048)
			(stroke
				(width 0.1)
				(type default)
			)
			(layer "F.Fab")
		)
		(fp_line
			(start 0.12065 -0.2794)
			(end 0.12065 -0.3048)
			(stroke
				(width 0.1)
				(type default)
			)
			(layer "F.Fab")
		)
		(fp_line
			(start -0.12065 -0.2794)
			(end 0.12065 -0.2794)
			(stroke
				(width 0.1)
				(type default)
			)
			(layer "F.Fab")
		)
		(fp_line
			(start 0.120396 0.2794)
			(end -0.12065 0.2794)
			(stroke
				(width 0.1)
				(type default)
			)
			(layer "F.Fab")
		)
		(fp_line
			(start -0.12065 0.2794)
			(end -0.12065 0.3048)
			(stroke
				(width 0.1)
				(type default)
			)
			(layer "F.Fab")
		)
		(fp_line
			(start 0.67945 0.3048)
			(end 0.120396 0.3048)
			(stroke
				(width 0.1)
				(type default)
			)
			(layer "F.Fab")
		)
		(fp_line
			(start 0.120396 0.3048)
			(end 0.120396 0.2794)
			(stroke
				(width 0.1)
				(type default)
			)
			(layer "F.Fab")
		)
		(fp_line
			(start -0.12065 0.3048)
			(end -0.67945 0.3048)
			(stroke
				(width 0.1)
				(type default)
			)
			(layer "F.Fab")
		)
		(fp_line
			(start -0.67945 0.3048)
			(end -0.67945 -0.305054)
			(stroke
				(width 0.1)
				(type default)
			)
			(layer "F.Fab")
		)
		(pad "1" smd circle
			(at -0.40005 0 90)
			(size 0 0)
			(layers "F.Cu" "F.Mask" "F.Paste")
			(net "V_DACG_R")
		)
		(pad "2" smd circle
			(at 0.40005 0 90)
			(size 0 0)
			(layers "F.Cu" "F.Mask" "F.Paste")
			(net "V_DACG")
		)
	)
	(footprint ""
		(layer "F.Cu")
		(at 11.29538 -67.4116 -90)
		(property "Reference" "C151"
			(at 0 0 270)
			(layer "F.SilkS")
			(hide yes)
			(effects
				(font
					(size 1.27 1.27)
				)
			)
		)
		(property "Value" ""
			(at 0 0 270)
			(layer "F.Fab")
			(effects
				(font
					(size 1.27 1.27)
				)
			)
		)
		(duplicate_pad_numbers_are_jumpers no)
		(fp_line
			(start -0.7874 0.4064)
			(end -0.7874 -0.4064)
			(stroke
				(width 0.1524)
				(type default)
			)
			(layer "F.SilkS")
		)
		(fp_line
			(start 0.7874 0.4064)
			(end -0.7874 0.4064)
			(stroke
				(width 0.1524)
				(type default)
			)
			(layer "F.SilkS")
		)
		(fp_line
			(start -0.7874 -0.4064)
			(end 0.7874 -0.4064)
			(stroke
				(width 0.1524)
				(type default)
			)
			(layer "F.SilkS")
		)
		(fp_line
			(start 0.7874 -0.4064)
			(end 0.7874 0.4064)
			(stroke
				(width 0.1524)
				(type default)
			)
			(layer "F.SilkS")
		)
		(fp_line
			(start -0.67945 0.3048)
			(end -0.67945 -0.305054)
			(stroke
				(width 0.1)
				(type default)
			)
			(layer "F.Fab")
		)
		(fp_line
			(start -0.12065 0.3048)
			(end -0.67945 0.3048)
			(stroke
				(width 0.1)
				(type default)
			)
			(layer "F.Fab")
		)
		(fp_line
			(start 0.120396 0.3048)
			(end 0.120396 0.2794)
			(stroke
				(width 0.1)
				(type default)
			)
			(layer "F.Fab")
		)
		(fp_line
			(start 0.67945 0.3048)
			(end 0.120396 0.3048)
			(stroke
				(width 0.1)
				(type default)
			)
			(layer "F.Fab")
		)
		(fp_line
			(start -0.12065 0.2794)
			(end -0.12065 0.3048)
			(stroke
				(width 0.1)
				(type default)
			)
			(layer "F.Fab")
		)
		(fp_line
			(start 0.120396 0.2794)
			(end -0.12065 0.2794)
			(stroke
				(width 0.1)
				(type default)
			)
			(layer "F.Fab")
		)
		(fp_line
			(start -0.12065 -0.2794)
			(end 0.12065 -0.2794)
			(stroke
				(width 0.1)
				(type default)
			)
			(layer "F.Fab")
		)
		(fp_line
			(start 0.12065 -0.2794)
			(end 0.12065 -0.3048)
			(stroke
				(width 0.1)
				(type default)
			)
			(layer "F.Fab")
		)
		(fp_line
			(start 0.12065 -0.3048)
			(end 0.67945 -0.3048)
			(stroke
				(width 0.1)
				(type default)
			)
			(layer "F.Fab")
		)
		(fp_line
			(start 0.67945 -0.3048)
			(end 0.67945 0.3048)
			(stroke
				(width 0.1)
				(type default)
			)
			(layer "F.Fab")
		)
		(fp_line
			(start -0.67945 -0.305054)
			(end -0.12065 -0.305054)
			(stroke
				(width 0.1)
				(type default)
			)
			(layer "F.Fab")
		)
		(fp_line
			(start -0.12065 -0.305054)
			(end -0.12065 -0.2794)
			(stroke
				(width 0.1)
				(type default)
			)
			(layer "F.Fab")
		)
		(pad "1" smd circle
			(at -0.40005 0 270)
			(size 0 0)
			(layers "F.Cu" "F.Mask" "F.Paste")
			(net "PWRGD_P3V3_AUX_R")
		)
		(pad "2" smd circle
			(at 0.40005 0 270)
			(size 0 0)
			(layers "F.Cu" "F.Mask" "F.Paste")
			(net "GND")
		)
	)
	(footprint ""
		(layer "F.Cu")
		(at 12.7762 -67.2084)
		(property "Reference" "R293"
			(at 0 0 0)
			(layer "F.SilkS")
			(hide yes)
			(effects
				(font
					(size 1.27 1.27)
				)
			)
		)
		(property "Value" ""
			(at 0 0 0)
			(layer "F.Fab")
			(effects
				(font
					(size 1.27 1.27)
				)
			)
		)
		(duplicate_pad_numbers_are_jumpers no)
		(fp_line
			(start -0.7874 -0.4064)
			(end 0.7874 -0.4064)
			(stroke
				(width 0.1524)
				(type default)
			)
			(layer "F.SilkS")
		)
		(fp_line
			(start -0.7874 0.4064)
			(end -0.7874 -0.4064)
			(stroke
				(width 0.1524)
				(type default)
			)
			(layer "F.SilkS")
		)
		(fp_line
			(start 0.7874 -0.4064)
			(end 0.7874 0.4064)
			(stroke
				(width 0.1524)
				(type default)
			)
			(layer "F.SilkS")
		)
		(fp_line
			(start 0.7874 0.4064)
			(end -0.7874 0.4064)
			(stroke
				(width 0.1524)
				(type default)
			)
			(layer "F.SilkS")
		)
		(fp_line
			(start -0.67945 -0.305054)
			(end -0.12065 -0.305054)
			(stroke
				(width 0.1)
				(type default)
			)
			(layer "F.Fab")
		)
		(fp_line
			(start -0.67945 0.3048)
			(end -0.67945 -0.305054)
			(stroke
				(width 0.1)
				(type default)
			)
			(layer "F.Fab")
		)
		(fp_line
			(start -0.12065 -0.305054)
			(end -0.12065 -0.2794)
			(stroke
				(width 0.1)
				(type default)
			)
			(layer "F.Fab")
		)
		(fp_line
			(start -0.12065 -0.2794)
			(end 0.12065 -0.2794)
			(stroke
				(width 0.1)
				(type default)
			)
			(layer "F.Fab")
		)
		(fp_line
			(start -0.12065 0.2794)
			(end -0.12065 0.3048)
			(stroke
				(width 0.1)
				(type default)
			)
			(layer "F.Fab")
		)
		(fp_line
			(start -0.12065 0.3048)
			(end -0.67945 0.3048)
			(stroke
				(width 0.1)
				(type default)
			)
			(layer "F.Fab")
		)
		(fp_line
			(start 0.120396 0.2794)
			(end -0.12065 0.2794)
			(stroke
				(width 0.1)
				(type default)
			)
			(layer "F.Fab")
		)
		(fp_line
			(start 0.120396 0.3048)
			(end 0.120396 0.2794)
			(stroke
				(width 0.1)
				(type default)
			)
			(layer "F.Fab")
		)
		(fp_line
			(start 0.12065 -0.3048)
			(end 0.67945 -0.3048)
			(stroke
				(width 0.1)
				(type default)
			)
			(layer "F.Fab")
		)
		(fp_line
			(start 0.12065 -0.2794)
			(end 0.12065 -0.3048)
			(stroke
				(width 0.1)
				(type default)
			)
			(layer "F.Fab")
		)
		(fp_line
			(start 0.67945 -0.3048)
			(end 0.67945 0.3048)
			(stroke
				(width 0.1)
				(type default)
			)
			(layer "F.Fab")
		)
		(fp_line
			(start 0.67945 0.3048)
			(end 0.120396 0.3048)
			(stroke
				(width 0.1)
				(type default)
			)
			(layer "F.Fab")
		)
		(pad "1" smd circle
			(at -0.40005 0)
			(size 0 0)
			(layers "F.Cu" "F.Mask" "F.Paste")
			(net "PWRGD_P3V3_AUX_R")
		)
		(pad "2" smd circle
			(at 0.40005 0)
			(size 0 0)
			(layers "F.Cu" "F.Mask" "F.Paste")
			(net "PWRGD_P3V3_AUX")
		)
	)
	(footprint ""
		(layer "F.Cu")
		(at 26.1112 -21.971 90)
		(property "Reference" "R29"
			(at 0 0 90)
			(layer "F.SilkS")
			(hide yes)
			(effects
				(font
					(size 1.27 1.27)
				)
			)
		)
		(property "Value" ""
			(at 0 0 90)
			(layer "F.Fab")
			(effects
				(font
					(size 1.27 1.27)
				)
			)
		)
		(duplicate_pad_numbers_are_jumpers no)
		(fp_line
			(start 0.7874 -0.4064)
			(end 0.7874 0.4064)
			(stroke
				(width 0.1524)
				(type default)
			)
			(layer "F.SilkS")
		)
		(fp_line
			(start -0.7874 -0.4064)
			(end 0.7874 -0.4064)
			(stroke
				(width 0.1524)
				(type default)
			)
			(layer "F.SilkS")
		)
		(fp_line
			(start 0.7874 0.4064)
			(end -0.7874 0.4064)
			(stroke
				(width 0.1524)
				(type default)
			)
			(layer "F.SilkS")
		)
		(fp_line
			(start -0.7874 0.4064)
			(end -0.7874 -0.4064)
			(stroke
				(width 0.1524)
				(type default)
			)
			(layer "F.SilkS")
		)
		(fp_line
			(start -0.12065 -0.305054)
			(end -0.12065 -0.2794)
			(stroke
				(width 0.1)
				(type default)
			)
			(layer "F.Fab")
		)
		(fp_line
			(start -0.67945 -0.305054)
			(end -0.12065 -0.305054)
			(stroke
				(width 0.1)
				(type default)
			)
			(layer "F.Fab")
		)
		(fp_line
			(start 0.67945 -0.3048)
			(end 0.67945 0.3048)
			(stroke
				(width 0.1)
				(type default)
			)
			(layer "F.Fab")
		)
		(fp_line
			(start 0.12065 -0.3048)
			(end 0.67945 -0.3048)
			(stroke
				(width 0.1)
				(type default)
			)
			(layer "F.Fab")
		)
		(fp_line
			(start 0.12065 -0.2794)
			(end 0.12065 -0.3048)
			(stroke
				(width 0.1)
				(type default)
			)
			(layer "F.Fab")
		)
		(fp_line
			(start -0.12065 -0.2794)
			(end 0.12065 -0.2794)
			(stroke
				(width 0.1)
				(type default)
			)
			(layer "F.Fab")
		)
		(fp_line
			(start 0.120396 0.2794)
			(end -0.12065 0.2794)
			(stroke
				(width 0.1)
				(type default)
			)
			(layer "F.Fab")
		)
		(fp_line
			(start -0.12065 0.2794)
			(end -0.12065 0.3048)
			(stroke
				(width 0.1)
				(type default)
			)
			(layer "F.Fab")
		)
		(fp_line
			(start 0.67945 0.3048)
			(end 0.120396 0.3048)
			(stroke
				(width 0.1)
				(type default)
			)
			(layer "F.Fab")
		)
		(fp_line
			(start 0.120396 0.3048)
			(end 0.120396 0.2794)
			(stroke
				(width 0.1)
				(type default)
			)
			(layer "F.Fab")
		)
		(fp_line
			(start -0.12065 0.3048)
			(end -0.67945 0.3048)
			(stroke
				(width 0.1)
				(type default)
			)
			(layer "F.Fab")
		)
		(fp_line
			(start -0.67945 0.3048)
			(end -0.67945 -0.305054)
			(stroke
				(width 0.1)
				(type default)
			)
			(layer "F.Fab")
		)
		(pad "1" smd circle
			(at -0.40005 0 90)
			(size 0 0)
			(layers "F.Cu" "F.Mask" "F.Paste")
			(net "V_BMC_LS_DDC_SDA")
		)
		(pad "2" smd circle
			(at 0.40005 0 90)
			(size 0 0)
			(layers "F.Cu" "F.Mask" "F.Paste")
			(net "V_BMC_LS_DDC_SDA_R")
		)
	)
	(footprint ""
		(layer "F.Cu")
		(at 59.99988 -107.700064)
		(property "Reference" "H4"
			(at -2.8702 -3.241548 0)
			(unlocked yes)
			(layer "F.SilkS")
			(effects
				(font
					(size 0.7874 0.5842)
					(thickness 0.1524)
				)
				(justify left)
			)
		)
		(property "Value" ""
			(at 0 0 0)
			(layer "F.Fab")
			(effects
				(font
					(size 1.27 1.27)
				)
			)
		)
		(duplicate_pad_numbers_are_jumpers no)
		(pad "1" thru_hole circle
			(at 0 0)
			(size 6.0198 6.0198)
			(drill 3.4036)
			(layers "*.Cu" "*.Mask")
			(remove_unused_layers no)
			(net "GND")
			(clearance -1.0541)
		)
	)
	(footprint ""
		(layer "F.Cu")
		(at 29.951172 -83.816952 90)
		(property "Reference" "R48"
			(at 0 0 90)
			(layer "F.SilkS")
			(hide yes)
			(effects
				(font
					(size 1.27 1.27)
				)
			)
		)
		(property "Value" ""
			(at 0 0 90)
			(layer "F.Fab")
			(effects
				(font
					(size 1.27 1.27)
				)
			)
		)
		(duplicate_pad_numbers_are_jumpers no)
		(fp_line
			(start 0.7874 -0.4064)
			(end 0.7874 0.4064)
			(stroke
				(width 0.1524)
				(type default)
			)
			(layer "F.SilkS")
		)
		(fp_line
			(start -0.7874 -0.4064)
			(end 0.7874 -0.4064)
			(stroke
				(width 0.1524)
				(type default)
			)
			(layer "F.SilkS")
		)
		(fp_line
			(start 0.7874 0.4064)
			(end -0.7874 0.4064)
			(stroke
				(width 0.1524)
				(type default)
			)
			(layer "F.SilkS")
		)
		(fp_line
			(start -0.7874 0.4064)
			(end -0.7874 -0.4064)
			(stroke
				(width 0.1524)
				(type default)
			)
			(layer "F.SilkS")
		)
		(fp_line
			(start -0.12065 -0.305054)
			(end -0.12065 -0.2794)
			(stroke
				(width 0.1)
				(type default)
			)
			(layer "F.Fab")
		)
		(fp_line
			(start -0.67945 -0.305054)
			(end -0.12065 -0.305054)
			(stroke
				(width 0.1)
				(type default)
			)
			(layer "F.Fab")
		)
		(fp_line
			(start 0.67945 -0.3048)
			(end 0.67945 0.3048)
			(stroke
				(width 0.1)
				(type default)
			)
			(layer "F.Fab")
		)
		(fp_line
			(start 0.12065 -0.3048)
			(end 0.67945 -0.3048)
			(stroke
				(width 0.1)
				(type default)
			)
			(layer "F.Fab")
		)
		(fp_line
			(start 0.12065 -0.2794)
			(end 0.12065 -0.3048)
			(stroke
				(width 0.1)
				(type default)
			)
			(layer "F.Fab")
		)
		(fp_line
			(start -0.12065 -0.2794)
			(end 0.12065 -0.2794)
			(stroke
				(width 0.1)
				(type default)
			)
			(layer "F.Fab")
		)
		(fp_line
			(start 0.120396 0.2794)
			(end -0.12065 0.2794)
			(stroke
				(width 0.1)
				(type default)
			)
			(layer "F.Fab")
		)
		(fp_line
			(start -0.12065 0.2794)
			(end -0.12065 0.3048)
			(stroke
				(width 0.1)
				(type default)
			)
			(layer "F.Fab")
		)
		(fp_line
			(start 0.67945 0.3048)
			(end 0.120396 0.3048)
			(stroke
				(width 0.1)
				(type default)
			)
			(layer "F.Fab")
		)
		(fp_line
			(start 0.120396 0.3048)
			(end 0.120396 0.2794)
			(stroke
				(width 0.1)
				(type default)
			)
			(layer "F.Fab")
		)
		(fp_line
			(start -0.12065 0.3048)
			(end -0.67945 0.3048)
			(stroke
				(width 0.1)
				(type default)
			)
			(layer "F.Fab")
		)
		(fp_line
			(start -0.67945 0.3048)
			(end -0.67945 -0.305054)
			(stroke
				(width 0.1)
				(type default)
			)
			(layer "F.Fab")
		)
		(pad "1" smd circle
			(at -0.40005 0 90)
			(size 0 0)
			(layers "F.Cu" "F.Mask" "F.Paste")
			(net "EMMC_CMD_R")
		)
		(pad "2" smd circle
			(at 0.40005 0 90)
			(size 0 0)
			(layers "F.Cu" "F.Mask" "F.Paste")
			(net "BMC_EMMC_CMD")
		)
	)
	(footprint ""
		(layer "F.Cu")
		(at 12.684252 -78.053184 90)
		(property "Reference" "PC225"
			(at 0 0 90)
			(layer "F.SilkS")
			(hide yes)
			(effects
				(font
					(size 1.27 1.27)
				)
			)
		)
		(property "Value" ""
			(at 0 0 90)
			(layer "F.Fab")
			(effects
				(font
					(size 1.27 1.27)
				)
			)
		)
		(duplicate_pad_numbers_are_jumpers no)
		(fp_line
			(start 0.7874 -0.4064)
			(end 0.7874 0.4064)
			(stroke
				(width 0.1524)
				(type default)
			)
			(layer "F.SilkS")
		)
		(fp_line
			(start -0.7874 -0.4064)
			(end 0.7874 -0.4064)
			(stroke
				(width 0.1524)
				(type default)
			)
			(layer "F.SilkS")
		)
		(fp_line
			(start 0.7874 0.4064)
			(end -0.7874 0.4064)
			(stroke
				(width 0.1524)
				(type default)
			)
			(layer "F.SilkS")
		)
		(fp_line
			(start -0.7874 0.4064)
			(end -0.7874 -0.4064)
			(stroke
				(width 0.1524)
				(type default)
			)
			(layer "F.SilkS")
		)
		(fp_line
			(start -0.12065 -0.305054)
			(end -0.12065 -0.2794)
			(stroke
				(width 0.1)
				(type default)
			)
			(layer "F.Fab")
		)
		(fp_line
			(start -0.67945 -0.305054)
			(end -0.12065 -0.305054)
			(stroke
				(width 0.1)
				(type default)
			)
			(layer "F.Fab")
		)
		(fp_line
			(start 0.67945 -0.3048)
			(end 0.67945 0.3048)
			(stroke
				(width 0.1)
				(type default)
			)
			(layer "F.Fab")
		)
		(fp_line
			(start 0.12065 -0.3048)
			(end 0.67945 -0.3048)
			(stroke
				(width 0.1)
				(type default)
			)
			(layer "F.Fab")
		)
		(fp_line
			(start 0.12065 -0.2794)
			(end 0.12065 -0.3048)
			(stroke
				(width 0.1)
				(type default)
			)
			(layer "F.Fab")
		)
		(fp_line
			(start -0.12065 -0.2794)
			(end 0.12065 -0.2794)
			(stroke
				(width 0.1)
				(type default)
			)
			(layer "F.Fab")
		)
		(fp_line
			(start 0.120396 0.2794)
			(end -0.12065 0.2794)
			(stroke
				(width 0.1)
				(type default)
			)
			(layer "F.Fab")
		)
		(fp_line
			(start -0.12065 0.2794)
			(end -0.12065 0.3048)
			(stroke
				(width 0.1)
				(type default)
			)
			(layer "F.Fab")
		)
		(fp_line
			(start 0.67945 0.3048)
			(end 0.120396 0.3048)
			(stroke
				(width 0.1)
				(type default)
			)
			(layer "F.Fab")
		)
		(fp_line
			(start 0.120396 0.3048)
			(end 0.120396 0.2794)
			(stroke
				(width 0.1)
				(type default)
			)
			(layer "F.Fab")
		)
		(fp_line
			(start -0.12065 0.3048)
			(end -0.67945 0.3048)
			(stroke
				(width 0.1)
				(type default)
			)
			(layer "F.Fab")
		)
		(fp_line
			(start -0.67945 0.3048)
			(end -0.67945 -0.305054)
			(stroke
				(width 0.1)
				(type default)
			)
			(layer "F.Fab")
		)
		(pad "1" smd circle
			(at -0.40005 0 90)
			(size 0 0)
			(layers "F.Cu" "F.Mask" "F.Paste")
			(net "P3V3_AUX")
		)
		(pad "2" smd circle
			(at 0.40005 0 90)
			(size 0 0)
			(layers "F.Cu" "F.Mask" "F.Paste")
			(net "GND")
		)
	)
)
